# S9S_MB_2U (Grand Teton) — schematic netlist excerpt (pin names and nets, part order shuffled) for the footprints in the layout excerpt that follows; sources: Cadence DE-HDL packaged netlist, KiCad conversion of 03242023_DA0F0TMBIJ0_F0T_Motherboard_J_brd_V01_OCP.brd

R4282  Q_RES  68K 1% CHIP  pkg 0402LF  page 169 : A = FM_USB3_1_EQB ; B = GND
R1713  Q_RES  4.7K 5% EMPTY  pkg 0402LF  page 266 : A = SMB_VR_3V3AUX_SCL_R3 ; B = P3V3_AUX

(kicad_pcb
	(version 20260206)
	(generator "pcbnew")
	(generator_version "10.0")
	(general
		(thickness 1.6)
		(legacy_teardrops no)
	)
	(paper "A4")
	(title_block
		(title "03242023_DA0F0TMBIJ0_F0T_Motherboard_J_brd_V01_OCP.brd")
		(comment 1 "Grand Teton / footprints 354-355 of 6105")
	)
	(layers
		(0 "F.Cu" signal "TOP")
		(4 "In1.Cu" signal "GND")
		(6 "In2.Cu" signal "IN1")
		(8 "In3.Cu" signal "GND1")
		(10 "In4.Cu" signal "IN2")
		(12 "In5.Cu" signal "GND2")
		(14 "In6.Cu" signal "IN3")
		(16 "In7.Cu" signal "GND3")
		(18 "In8.Cu" signal "VCC")
		(20 "In9.Cu" signal "VCC1")
		(22 "In10.Cu" signal "GND4")
		(24 "In11.Cu" signal "IN4")
		(26 "In12.Cu" signal "GND5")
		(28 "In13.Cu" signal "IN5")
		(30 "In14.Cu" signal "GND6")
		(32 "In15.Cu" signal "IN6")
		(34 "In16.Cu" signal "GND7")
		(2 "B.Cu" signal "BOTTOM")
		(9 "F.Adhes" user "F.Adhesive")
		(11 "B.Adhes" user "B.Adhesive")
		(13 "F.Paste" user "Package Geometry/Pastemask Top")
		(15 "B.Paste" user "Package Geometry/Pastemask Bottom")
		(5 "F.SilkS" user "Ref Des/Silkscreen Top")
		(7 "B.SilkS" user "Ref Des/Silkscreen Bottom")
		(1 "F.Mask" user "Board Geometry/Soldermask Top")
		(3 "B.Mask" user "Board Geometry/Soldermask Bottom")
		(17 "Dwgs.User" user "User.Drawings")
		(19 "Cmts.User" user "User.Comments")
		(21 "Eco1.User" user "User.Eco1")
		(23 "Eco2.User" user "User.Eco2")
		(25 "Edge.Cuts" user "Board Geometry/Outline")
		(27 "Margin" user)
		(31 "F.CrtYd" user "Package Geometry/Place Bound Top")
		(29 "B.CrtYd" user "Package Geometry/Place Bound Bottom")
		(35 "F.Fab" user "Ref Des/Assembly Top")
		(33 "B.Fab" user "Ref Des/Assembly Bottom")
	)
	(footprint ""
		(layer "F.Cu")
		(at 136.62406 -27.447748)
		(property "Reference" "R4282"
			(at 0 0 0)
			(layer "F.SilkS")
			(hide yes)
			(effects
				(font
					(size 1.27 1.27)
				)
			)
		)
		(property "Value" ""
			(at 0 0 0)
			(layer "F.Fab")
			(effects
				(font
					(size 1.27 1.27)
				)
			)
		)
		(duplicate_pad_numbers_are_jumpers no)
		(fp_line
			(start -0.7874 -0.4064)
			(end 0.7874 -0.4064)
			(stroke
				(width 0.1524)
				(type default)
			)
			(layer "F.SilkS")
		)
		(fp_line
			(start -0.7874 0.4064)
			(end -0.7874 -0.4064)
			(stroke
				(width 0.1524)
				(type default)
			)
			(layer "F.SilkS")
		)
		(fp_line
			(start 0.7874 -0.4064)
			(end 0.7874 0.4064)
			(stroke
				(width 0.1524)
				(type default)
			)
			(layer "F.SilkS")
		)
		(fp_line
			(start 0.7874 0.4064)
			(end -0.7874 0.4064)
			(stroke
				(width 0.1524)
				(type default)
			)
			(layer "F.SilkS")
		)
		(fp_line
			(start -0.67945 -0.305054)
			(end -0.12065 -0.305054)
			(stroke
				(width 0.1)
				(type default)
			)
			(layer "F.Fab")
		)
		(fp_line
			(start -0.67945 0.3048)
			(end -0.67945 -0.305054)
			(stroke
				(width 0.1)
				(type default)
			)
			(layer "F.Fab")
		)
		(fp_line
			(start -0.12065 -0.305054)
			(end -0.12065 -0.2794)
			(stroke
				(width 0.1)
				(type default)
			)
			(layer "F.Fab")
		)
		(fp_line
			(start -0.12065 -0.2794)
			(end 0.12065 -0.2794)
			(stroke
				(width 0.1)
				(type default)
			)
			(layer "F.Fab")
		)
		(fp_line
			(start -0.12065 0.2794)
			(end -0.12065 0.3048)
			(stroke
				(width 0.1)
				(type default)
			)
			(layer "F.Fab")
		)
		(fp_line
			(start -0.12065 0.3048)
			(end -0.67945 0.3048)
			(stroke
				(width 0.1)
				(type default)
			)
			(layer "F.Fab")
		)
		(fp_line
			(start 0.120396 0.2794)
			(end -0.12065 0.2794)
			(stroke
				(width 0.1)
				(type default)
			)
			(layer "F.Fab")
		)
		(fp_line
			(start 0.120396 0.3048)
			(end 0.120396 0.2794)
			(stroke
				(width 0.1)
				(type default)
			)
			(layer "F.Fab")
		)
		(fp_line
			(start 0.12065 -0.3048)
			(end 0.67945 -0.3048)
			(stroke
				(width 0.1)
				(type default)
			)
			(layer "F.Fab")
		)
		(fp_line
			(start 0.12065 -0.2794)
			(end 0.12065 -0.3048)
			(stroke
				(width 0.1)
				(type default)
			)
			(layer "F.Fab")
		)
		(fp_line
			(start 0.67945 -0.3048)
			(end 0.67945 0.3048)
			(stroke
				(width 0.1)
				(type default)
			)
			(layer "F.Fab")
		)
		(fp_line
			(start 0.67945 0.3048)
			(end 0.120396 0.3048)
			(stroke
				(width 0.1)
				(type default)
			)
			(layer "F.Fab")
		)
		(pad "1" smd circle
			(at -0.40005 0)
			(size 0 0)
			(layers "F.Cu" "F.Mask" "F.Paste")
			(net "FM_USB3_1_EQB")
		)
		(pad "2" smd circle
			(at 0.40005 0)
			(size 0 0)
			(layers "F.Cu" "F.Mask" "F.Paste")
			(net "GND")
		)
	)
	(footprint ""
		(layer "F.Cu")
		(at 140.208 -368.645948 -90)
		(property "Reference" "R1713"
			(at 0 0 270)
			(layer "F.SilkS")
			(hide yes)
			(effects
				(font
					(size 1.27 1.27)
				)
			)
		)
		(property "Value" ""
			(at 0 0 270)
			(layer "F.Fab")
			(effects
				(font
					(size 1.27 1.27)
				)
			)
		)
		(duplicate_pad_numbers_are_jumpers no)
		(fp_line
			(start -0.7874 0.4064)
			(end -0.7874 -0.4064)
			(stroke
				(width 0.1524)
				(type default)
			)
			(layer "F.SilkS")
		)
		(fp_line
			(start 0.7874 0.4064)
			(end -0.7874 0.4064)
			(stroke
				(width 0.1524)
				(type default)
			)
			(layer "F.SilkS")
		)
		(fp_line
			(start -0.7874 -0.4064)
			(end 0.7874 -0.4064)
			(stroke
				(width 0.1524)
				(type default)
			)
			(layer "F.SilkS")
		)
		(fp_line
			(start 0.7874 -0.4064)
			(end 0.7874 0.4064)
			(stroke
				(width 0.1524)
				(type default)
			)
			(layer "F.SilkS")
		)
		(fp_line
			(start -0.67945 0.3048)
			(end -0.67945 -0.305054)
			(stroke
				(width 0.1)
				(type default)
			)
			(layer "F.Fab")
		)
		(fp_line
			(start -0.12065 0.3048)
			(end -0.67945 0.3048)
			(stroke
				(width 0.1)
				(type default)
			)
			(layer "F.Fab")
		)
		(fp_line
			(start 0.120396 0.3048)
			(end 0.120396 0.2794)
			(stroke
				(width 0.1)
				(type default)
			)
			(layer "F.Fab")
		)
		(fp_line
			(start 0.67945 0.3048)
			(end 0.120396 0.3048)
			(stroke
				(width 0.1)
				(type default)
			)
			(layer "F.Fab")
		)
		(fp_line
			(start -0.12065 0.2794)
			(end -0.12065 0.3048)
			(stroke
				(width 0.1)
				(type default)
			)
			(layer "F.Fab")
		)
		(fp_line
			(start 0.120396 0.2794)
			(end -0.12065 0.2794)
			(stroke
				(width 0.1)
				(type default)
			)
			(layer "F.Fab")
		)
		(fp_line
			(start -0.12065 -0.2794)
			(end 0.12065 -0.2794)
			(stroke
				(width 0.1)
				(type default)
			)
			(layer "F.Fab")
		)
		(fp_line
			(start 0.12065 -0.2794)
			(end 0.12065 -0.3048)
			(stroke
				(width 0.1)
				(type default)
			)
			(layer "F.Fab")
		)
		(fp_line
			(start 0.12065 -0.3048)
			(end 0.67945 -0.3048)
			(stroke
				(width 0.1)
				(type default)
			)
			(layer "F.Fab")
		)
		(fp_line
			(start 0.67945 -0.3048)
			(end 0.67945 0.3048)
			(stroke
				(width 0.1)
				(type default)
			)
			(layer "F.Fab")
		)
		(fp_line
			(start -0.67945 -0.305054)
			(end -0.12065 -0.305054)
			(stroke
				(width 0.1)
				(type default)
			)
			(layer "F.Fab")
		)
		(fp_line
			(start -0.12065 -0.305054)
			(end -0.12065 -0.2794)
			(stroke
				(width 0.1)
				(type default)
			)
			(layer "F.Fab")
		)
		(pad "1" smd circle
			(at -0.40005 0 270)
			(size 0 0)
			(layers "F.Cu" "F.Mask" "F.Paste")
			(net "SMB_VR_3V3AUX_SCL_R3")
		)
		(pad "2" smd circle
			(at 0.40005 0 270)
			(size 0 0)
			(layers "F.Cu" "F.Mask" "F.Paste")
			(net "P3V3_AUX")
		)
	)
)
